# S9S_MB_2U (Grand Teton) — schematic netlist excerpt (pin names and nets, part order shuffled) for the footprints in the layout excerpt that follows; sources: Cadence DE-HDL packaged netlist, KiCad conversion of 03242023_DA0F0TMBIJ0_F0T_Motherboard_J_brd_V01_OCP.brd

R4756  Q_RES  10K 1% CHIP  pkg 0402LF  page 164 : A = P3V3_AUX ; B = OCP_V3_2_AUX_PWR_PLD_EN_R
R3294  Q_RES  0 5% CHIP  pkg 0402LF  page 190 : A = LED_M2_SSD_0_ACT_N ; B = LED_HDD_ACTIVITY_N
C898  Q_CAP_DIFFBUS  DIFF BUS_0.22UF 6.3V 20% X6S  pkg C0201  page 174 : \1\ = P5E_CPU0_PE3_TX_C_DN<1> ; \2\ = P5E_CPU0_PE3_TX_DN<1>

(kicad_pcb
	(version 20260206)
	(generator "pcbnew")
	(generator_version "10.0")
	(general
		(thickness 1.6)
		(legacy_teardrops no)
	)
	(paper "A4")
	(title_block
		(title "03242023_DA0F0TMBIJ0_F0T_Motherboard_J_brd_V01_OCP.brd")
		(comment 1 "Grand Teton / footprints 3249-3251 of 6105")
	)
	(layers
		(0 "F.Cu" signal "TOP")
		(4 "In1.Cu" signal "GND")
		(6 "In2.Cu" signal "IN1")
		(8 "In3.Cu" signal "GND1")
		(10 "In4.Cu" signal "IN2")
		(12 "In5.Cu" signal "GND2")
		(14 "In6.Cu" signal "IN3")
		(16 "In7.Cu" signal "GND3")
		(18 "In8.Cu" signal "VCC")
		(20 "In9.Cu" signal "VCC1")
		(22 "In10.Cu" signal "GND4")
		(24 "In11.Cu" signal "IN4")
		(26 "In12.Cu" signal "GND5")
		(28 "In13.Cu" signal "IN5")
		(30 "In14.Cu" signal "GND6")
		(32 "In15.Cu" signal "IN6")
		(34 "In16.Cu" signal "GND7")
		(2 "B.Cu" signal "BOTTOM")
		(9 "F.Adhes" user "F.Adhesive")
		(11 "B.Adhes" user "B.Adhesive")
		(13 "F.Paste" user "Package Geometry/Pastemask Top")
		(15 "B.Paste" user "Package Geometry/Pastemask Bottom")
		(5 "F.SilkS" user "Ref Des/Silkscreen Top")
		(7 "B.SilkS" user "Ref Des/Silkscreen Bottom")
		(1 "F.Mask" user "Board Geometry/Soldermask Top")
		(3 "B.Mask" user "Board Geometry/Soldermask Bottom")
		(17 "Dwgs.User" user "User.Drawings")
		(19 "Cmts.User" user "User.Comments")
		(21 "Eco1.User" user "User.Eco1")
		(23 "Eco2.User" user "User.Eco2")
		(25 "Edge.Cuts" user "Board Geometry/Outline")
		(27 "Margin" user)
		(31 "F.CrtYd" user "Package Geometry/Place Bound Top")
		(29 "B.CrtYd" user "Package Geometry/Place Bound Bottom")
		(35 "F.Fab" user "Ref Des/Assembly Top")
		(33 "B.Fab" user "Ref Des/Assembly Bottom")
	)
	(footprint ""
		(layer "F.Cu")
		(at 136.3853 -113.384584)
		(property "Reference" "R4756"
			(at 0 0 0)
			(layer "F.SilkS")
			(hide yes)
			(effects
				(font
					(size 1.27 1.27)
				)
			)
		)
		(property "Value" ""
			(at 0 0 0)
			(layer "F.Fab")
			(effects
				(font
					(size 1.27 1.27)
				)
			)
		)
		(duplicate_pad_numbers_are_jumpers no)
		(fp_line
			(start -0.7874 -0.4064)
			(end 0.7874 -0.4064)
			(stroke
				(width 0.1524)
				(type default)
			)
			(layer "F.SilkS")
		)
		(fp_line
			(start -0.7874 0.4064)
			(end -0.7874 -0.4064)
			(stroke
				(width 0.1524)
				(type default)
			)
			(layer "F.SilkS")
		)
		(fp_line
			(start 0.7874 -0.4064)
			(end 0.7874 0.4064)
			(stroke
				(width 0.1524)
				(type default)
			)
			(layer "F.SilkS")
		)
		(fp_line
			(start 0.7874 0.4064)
			(end -0.7874 0.4064)
			(stroke
				(width 0.1524)
				(type default)
			)
			(layer "F.SilkS")
		)
		(fp_line
			(start -0.67945 -0.305054)
			(end -0.12065 -0.305054)
			(stroke
				(width 0.1)
				(type default)
			)
			(layer "F.Fab")
		)
		(fp_line
			(start -0.67945 0.3048)
			(end -0.67945 -0.305054)
			(stroke
				(width 0.1)
				(type default)
			)
			(layer "F.Fab")
		)
		(fp_line
			(start -0.12065 -0.305054)
			(end -0.12065 -0.2794)
			(stroke
				(width 0.1)
				(type default)
			)
			(layer "F.Fab")
		)
		(fp_line
			(start -0.12065 -0.2794)
			(end 0.12065 -0.2794)
			(stroke
				(width 0.1)
				(type default)
			)
			(layer "F.Fab")
		)
		(fp_line
			(start -0.12065 0.2794)
			(end -0.12065 0.3048)
			(stroke
				(width 0.1)
				(type default)
			)
			(layer "F.Fab")
		)
		(fp_line
			(start -0.12065 0.3048)
			(end -0.67945 0.3048)
			(stroke
				(width 0.1)
				(type default)
			)
			(layer "F.Fab")
		)
		(fp_line
			(start 0.120396 0.2794)
			(end -0.12065 0.2794)
			(stroke
				(width 0.1)
				(type default)
			)
			(layer "F.Fab")
		)
		(fp_line
			(start 0.120396 0.3048)
			(end 0.120396 0.2794)
			(stroke
				(width 0.1)
				(type default)
			)
			(layer "F.Fab")
		)
		(fp_line
			(start 0.12065 -0.3048)
			(end 0.67945 -0.3048)
			(stroke
				(width 0.1)
				(type default)
			)
			(layer "F.Fab")
		)
		(fp_line
			(start 0.12065 -0.2794)
			(end 0.12065 -0.3048)
			(stroke
				(width 0.1)
				(type default)
			)
			(layer "F.Fab")
		)
		(fp_line
			(start 0.67945 -0.3048)
			(end 0.67945 0.3048)
			(stroke
				(width 0.1)
				(type default)
			)
			(layer "F.Fab")
		)
		(fp_line
			(start 0.67945 0.3048)
			(end 0.120396 0.3048)
			(stroke
				(width 0.1)
				(type default)
			)
			(layer "F.Fab")
		)
		(pad "1" smd circle
			(at -0.40005 0)
			(size 0 0)
			(layers "F.Cu" "F.Mask" "F.Paste")
			(net "P3V3_AUX")
		)
		(pad "2" smd circle
			(at 0.40005 0)
			(size 0 0)
			(layers "F.Cu" "F.Mask" "F.Paste")
			(net "OCP_V3_2_AUX_PWR_PLD_EN_R")
		)
	)
	(footprint ""
		(layer "F.Cu")
		(at 415.62909 -408.517344 -90)
		(property "Reference" "C898"
			(at 0 0 270)
			(layer "F.SilkS")
			(hide yes)
			(effects
				(font
					(size 1.27 1.27)
				)
			)
		)
		(property "Value" ""
			(at 0 0 270)
			(layer "F.Fab")
			(effects
				(font
					(size 1.27 1.27)
				)
			)
		)
		(duplicate_pad_numbers_are_jumpers no)
		(fp_line
			(start -0.299974 0.150114)
			(end -0.299974 -0.150114)
			(stroke
				(width 0.1)
				(type default)
			)
			(layer "F.Fab")
		)
		(fp_line
			(start 0.299974 0.150114)
			(end -0.299974 0.150114)
			(stroke
				(width 0.1)
				(type default)
			)
			(layer "F.Fab")
		)
		(fp_line
			(start -0.299974 -0.150114)
			(end 0.299974 -0.150114)
			(stroke
				(width 0.1)
				(type default)
			)
			(layer "F.Fab")
		)
		(fp_line
			(start 0.299974 -0.150114)
			(end 0.299974 0.150114)
			(stroke
				(width 0.1)
				(type default)
			)
			(layer "F.Fab")
		)
		(pad "1" smd rect
			(at -0.2667 0 270)
			(size 0.3048 0.381)
			(layers "F.Cu" "F.Mask" "F.Paste")
			(net "P5E_CPU0_PE3_TX_C_DN<1>")
		)
		(pad "2" smd rect
			(at 0.2667 0 270)
			(size 0.3048 0.381)
			(layers "F.Cu" "F.Mask" "F.Paste")
			(net "P5E_CPU0_PE3_TX_DN<1>")
		)
	)
	(footprint ""
		(layer "F.Cu")
		(at 142.42288 -42.446448)
		(property "Reference" "R3294"
			(at 0 0 0)
			(layer "F.SilkS")
			(hide yes)
			(effects
				(font
					(size 1.27 1.27)
				)
			)
		)
		(property "Value" ""
			(at 0 0 0)
			(layer "F.Fab")
			(effects
				(font
					(size 1.27 1.27)
				)
			)
		)
		(duplicate_pad_numbers_are_jumpers no)
		(fp_line
			(start -0.7874 -0.4064)
			(end 0.7874 -0.4064)
			(stroke
				(width 0.1524)
				(type default)
			)
			(layer "F.SilkS")
		)
		(fp_line
			(start -0.7874 0.4064)
			(end -0.7874 -0.4064)
			(stroke
				(width 0.1524)
				(type default)
			)
			(layer "F.SilkS")
		)
		(fp_line
			(start 0.7874 -0.4064)
			(end 0.7874 0.4064)
			(stroke
				(width 0.1524)
				(type default)
			)
			(layer "F.SilkS")
		)
		(fp_line
			(start 0.7874 0.4064)
			(end -0.7874 0.4064)
			(stroke
				(width 0.1524)
				(type default)
			)
			(layer "F.SilkS")
		)
		(fp_line
			(start -0.67945 -0.305054)
			(end -0.12065 -0.305054)
			(stroke
				(width 0.1)
				(type default)
			)
			(layer "F.Fab")
		)
		(fp_line
			(start -0.67945 0.3048)
			(end -0.67945 -0.305054)
			(stroke
				(width 0.1)
				(type default)
			)
			(layer "F.Fab")
		)
		(fp_line
			(start -0.12065 -0.305054)
			(end -0.12065 -0.2794)
			(stroke
				(width 0.1)
				(type default)
			)
			(layer "F.Fab")
		)
		(fp_line
			(start -0.12065 -0.2794)
			(end 0.12065 -0.2794)
			(stroke
				(width 0.1)
				(type default)
			)
			(layer "F.Fab")
		)
		(fp_line
			(start -0.12065 0.2794)
			(end -0.12065 0.3048)
			(stroke
				(width 0.1)
				(type default)
			)
			(layer "F.Fab")
		)
		(fp_line
			(start -0.12065 0.3048)
			(end -0.67945 0.3048)
			(stroke
				(width 0.1)
				(type default)
			)
			(layer "F.Fab")
		)
		(fp_line
			(start 0.120396 0.2794)
			(end -0.12065 0.2794)
			(stroke
				(width 0.1)
				(type default)
			)
			(layer "F.Fab")
		)
		(fp_line
			(start 0.120396 0.3048)
			(end 0.120396 0.2794)
			(stroke
				(width 0.1)
				(type default)
			)
			(layer "F.Fab")
		)
		(fp_line
			(start 0.12065 -0.3048)
			(end 0.67945 -0.3048)
			(stroke
				(width 0.1)
				(type default)
			)
			(layer "F.Fab")
		)
		(fp_line
			(start 0.12065 -0.2794)
			(end 0.12065 -0.3048)
			(stroke
				(width 0.1)
				(type default)
			)
			(layer "F.Fab")
		)
		(fp_line
			(start 0.67945 -0.3048)
			(end 0.67945 0.3048)
			(stroke
				(width 0.1)
				(type default)
			)
			(layer "F.Fab")
		)
		(fp_line
			(start 0.67945 0.3048)
			(end 0.120396 0.3048)
			(stroke
				(width 0.1)
				(type default)
			)
			(layer "F.Fab")
		)
		(pad "1" smd circle
			(at -0.40005 0)
			(size 0 0)
			(layers "F.Cu" "F.Mask" "F.Paste")
			(net "LED_M2_SSD_0_ACT_N")
		)
		(pad "2" smd circle
			(at 0.40005 0)
			(size 0 0)
			(layers "F.Cu" "F.Mask" "F.Paste")
			(net "LED_HDD_ACTIVITY_N")
		)
	)
)
